(kicad_pcb
	(version 20260206)
	(generator "pcbnew")
	(generator_version "10.0")
	(general
		(thickness 1.6)
		(legacy_teardrops no)
	)
	(paper "A4")
	(title_block
		(title "04192023_DAF0TMB3IC0_F0TG_MB_C_brd_V02_OCP.brd")
		(comment 1 "Grand Teton / footprints 1245-1250 of 8354")
	)
	(layers
		(0 "F.Cu" signal "TOP")
		(4 "In1.Cu" signal "GND")
		(6 "In2.Cu" signal "IN1")
		(8 "In3.Cu" signal "GND1")
		(10 "In4.Cu" signal "IN2")
		(12 "In5.Cu" signal "GND2")
		(14 "In6.Cu" signal "IN3")
		(16 "In7.Cu" signal "GND3")
		(18 "In8.Cu" signal "VCC")
		(20 "In9.Cu" signal "VCC1")
		(22 "In10.Cu" signal "GND4")
		(24 "In11.Cu" signal "IN4")
		(26 "In12.Cu" signal "GND5")
		(28 "In13.Cu" signal "IN5")
		(30 "In14.Cu" signal "GND6")
		(32 "In15.Cu" signal "IN6")
		(34 "In16.Cu" signal "GND7")
		(2 "B.Cu" signal "BOTTOM")
		(9 "F.Adhes" user "F.Adhesive")
		(11 "B.Adhes" user "B.Adhesive")
		(13 "F.Paste" user "Package Geometry/Pastemask Top")
		(15 "B.Paste" user "Package Geometry/Pastemask Bottom")
		(5 "F.SilkS" user "Ref Des/Silkscreen Top")
		(7 "B.SilkS" user "Ref Des/Silkscreen Bottom")
		(1 "F.Mask" user "Board Geometry/Soldermask Top")
		(3 "B.Mask" user "Board Geometry/Soldermask Bottom")
		(17 "Dwgs.User" user "User.Drawings")
		(19 "Cmts.User" user "User.Comments")
		(21 "Eco1.User" user "User.Eco1")
		(23 "Eco2.User" user "User.Eco2")
		(25 "Edge.Cuts" user "Board Geometry/Outline")
		(27 "Margin" user)
		(31 "F.CrtYd" user "Package Geometry/Place Bound Top")
		(29 "B.CrtYd" user "Package Geometry/Place Bound Bottom")
		(35 "F.Fab" user "Ref Des/Assembly Top")
		(33 "B.Fab" user "Ref Des/Assembly Bottom")
	)
	(footprint ""
		(layer "F.Cu")
		(at 211.76361 -57.548272 -90)
		(property "Reference" "R3763"
			(at 0 0 270)
			(layer "F.SilkS")
			(hide yes)
			(effects
				(font
					(size 1.27 1.27)
				)
			)
		)
		(property "Value" ""
			(at 0 0 270)
			(layer "F.Fab")
			(effects
				(font
					(size 1.27 1.27)
				)
			)
		)
		(duplicate_pad_numbers_are_jumpers no)
		(fp_line
			(start -0.7874 0.4064)
			(end -0.7874 -0.4064)
			(stroke
				(width 0.1524)
				(type default)
			)
			(layer "F.SilkS")
		)
		(fp_line
			(start 0.7874 0.4064)
			(end -0.7874 0.4064)
			(stroke
				(width 0.1524)
				(type default)
			)
			(layer "F.SilkS")
		)
		(fp_line
			(start -0.7874 -0.4064)
			(end 0.7874 -0.4064)
			(stroke
				(width 0.1524)
				(type default)
			)
			(layer "F.SilkS")
		)
		(fp_line
			(start 0.7874 -0.4064)
			(end 0.7874 0.4064)
			(stroke
				(width 0.1524)
				(type default)
			)
			(layer "F.SilkS")
		)
		(fp_line
			(start -0.67945 0.3048)
			(end -0.67945 -0.305054)
			(stroke
				(width 0.1)
				(type default)
			)
			(layer "F.Fab")
		)
		(fp_line
			(start -0.12065 0.3048)
			(end -0.67945 0.3048)
			(stroke
				(width 0.1)
				(type default)
			)
			(layer "F.Fab")
		)
		(fp_line
			(start 0.120396 0.3048)
			(end 0.120396 0.2794)
			(stroke
				(width 0.1)
				(type default)
			)
			(layer "F.Fab")
		)
		(fp_line
			(start 0.67945 0.3048)
			(end 0.120396 0.3048)
			(stroke
				(width 0.1)
				(type default)
			)
			(layer "F.Fab")
		)
		(fp_line
			(start -0.12065 0.2794)
			(end -0.12065 0.3048)
			(stroke
				(width 0.1)
				(type default)
			)
			(layer "F.Fab")
		)
		(fp_line
			(start 0.120396 0.2794)
			(end -0.12065 0.2794)
			(stroke
				(width 0.1)
				(type default)
			)
			(layer "F.Fab")
		)
		(fp_line
			(start -0.12065 -0.2794)
			(end 0.12065 -0.2794)
			(stroke
				(width 0.1)
				(type default)
			)
			(layer "F.Fab")
		)
		(fp_line
			(start 0.12065 -0.2794)
			(end 0.12065 -0.3048)
			(stroke
				(width 0.1)
				(type default)
			)
			(layer "F.Fab")
		)
		(fp_line
			(start 0.12065 -0.3048)
			(end 0.67945 -0.3048)
			(stroke
				(width 0.1)
				(type default)
			)
			(layer "F.Fab")
		)
		(fp_line
			(start 0.67945 -0.3048)
			(end 0.67945 0.3048)
			(stroke
				(width 0.1)
				(type default)
			)
			(layer "F.Fab")
		)
		(fp_line
			(start -0.67945 -0.305054)
			(end -0.12065 -0.305054)
			(stroke
				(width 0.1)
				(type default)
			)
			(layer "F.Fab")
		)
		(fp_line
			(start -0.12065 -0.305054)
			(end -0.12065 -0.2794)
			(stroke
				(width 0.1)
				(type default)
			)
			(layer "F.Fab")
		)
		(pad "1" smd circle
			(at -0.40005 0 270)
			(size 0 0)
			(layers "F.Cu" "F.Mask" "F.Paste")
			(net "GND")
		)
		(pad "2" smd circle
			(at 0.40005 0 270)
			(size 0 0)
			(layers "F.Cu" "F.Mask" "F.Paste")
			(net "INA230_2_A1")
		)
	)
	(footprint ""
		(layer "F.Cu")
		(at 123.127516 -57.137808 90)
		(property "Reference" "C1504"
			(at 0 0 90)
			(layer "F.SilkS")
			(hide yes)
			(effects
				(font
					(size 1.27 1.27)
				)
			)
		)
		(property "Value" ""
			(at 0 0 90)
			(layer "F.Fab")
			(effects
				(font
					(size 1.27 1.27)
				)
			)
		)
		(duplicate_pad_numbers_are_jumpers no)
		(fp_line
			(start 0.7874 -0.4064)
			(end 0.7874 0.4064)
			(stroke
				(width 0.1524)
				(type default)
			)
			(layer "F.SilkS")
		)
		(fp_line
			(start -0.7874 -0.4064)
			(end 0.7874 -0.4064)
			(stroke
				(width 0.1524)
				(type default)
			)
			(layer "F.SilkS")
		)
		(fp_line
			(start 0.7874 0.4064)
			(end -0.7874 0.4064)
			(stroke
				(width 0.1524)
				(type default)
			)
			(layer "F.SilkS")
		)
		(fp_line
			(start -0.7874 0.4064)
			(end -0.7874 -0.4064)
			(stroke
				(width 0.1524)
				(type default)
			)
			(layer "F.SilkS")
		)
		(fp_line
			(start -0.12065 -0.305054)
			(end -0.12065 -0.2794)
			(stroke
				(width 0.1)
				(type default)
			)
			(layer "F.Fab")
		)
		(fp_line
			(start -0.67945 -0.305054)
			(end -0.12065 -0.305054)
			(stroke
				(width 0.1)
				(type default)
			)
			(layer "F.Fab")
		)
		(fp_line
			(start 0.67945 -0.3048)
			(end 0.67945 0.3048)
			(stroke
				(width 0.1)
				(type default)
			)
			(layer "F.Fab")
		)
		(fp_line
			(start 0.12065 -0.3048)
			(end 0.67945 -0.3048)
			(stroke
				(width 0.1)
				(type default)
			)
			(layer "F.Fab")
		)
		(fp_line
			(start 0.12065 -0.2794)
			(end 0.12065 -0.3048)
			(stroke
				(width 0.1)
				(type default)
			)
			(layer "F.Fab")
		)
		(fp_line
			(start -0.12065 -0.2794)
			(end 0.12065 -0.2794)
			(stroke
				(width 0.1)
				(type default)
			)
			(layer "F.Fab")
		)
		(fp_line
			(start 0.120396 0.2794)
			(end -0.12065 0.2794)
			(stroke
				(width 0.1)
				(type default)
			)
			(layer "F.Fab")
		)
		(fp_line
			(start -0.12065 0.2794)
			(end -0.12065 0.3048)
			(stroke
				(width 0.1)
				(type default)
			)
			(layer "F.Fab")
		)
		(fp_line
			(start 0.67945 0.3048)
			(end 0.120396 0.3048)
			(stroke
				(width 0.1)
				(type default)
			)
			(layer "F.Fab")
		)
		(fp_line
			(start 0.120396 0.3048)
			(end 0.120396 0.2794)
			(stroke
				(width 0.1)
				(type default)
			)
			(layer "F.Fab")
		)
		(fp_line
			(start -0.12065 0.3048)
			(end -0.67945 0.3048)
			(stroke
				(width 0.1)
				(type default)
			)
			(layer "F.Fab")
		)
		(fp_line
			(start -0.67945 0.3048)
			(end -0.67945 -0.305054)
			(stroke
				(width 0.1)
				(type default)
			)
			(layer "F.Fab")
		)
		(pad "1" smd circle
			(at -0.40005 0 90)
			(size 0 0)
			(layers "F.Cu" "F.Mask" "F.Paste")
			(net "PVDD18_S5_P0")
		)
		(pad "2" smd circle
			(at 0.40005 0 90)
			(size 0 0)
			(layers "F.Cu" "F.Mask" "F.Paste")
			(net "GND")
		)
	)
	(footprint ""
		(layer "F.Cu")
		(at 75.705462 -38.532562)
		(property "Reference" "C2012"
			(at 0 0 0)
			(layer "F.SilkS")
			(hide yes)
			(effects
				(font
					(size 1.27 1.27)
				)
			)
		)
		(property "Value" ""
			(at 0 0 0)
			(layer "F.Fab")
			(effects
				(font
					(size 1.27 1.27)
				)
			)
		)
		(duplicate_pad_numbers_are_jumpers no)
		(fp_line
			(start -0.7874 -0.4064)
			(end 0.7874 -0.4064)
			(stroke
				(width 0.1524)
				(type default)
			)
			(layer "F.SilkS")
		)
		(fp_line
			(start -0.7874 0.4064)
			(end -0.7874 -0.4064)
			(stroke
				(width 0.1524)
				(type default)
			)
			(layer "F.SilkS")
		)
		(fp_line
			(start 0.7874 -0.4064)
			(end 0.7874 0.4064)
			(stroke
				(width 0.1524)
				(type default)
			)
			(layer "F.SilkS")
		)
		(fp_line
			(start 0.7874 0.4064)
			(end -0.7874 0.4064)
			(stroke
				(width 0.1524)
				(type default)
			)
			(layer "F.SilkS")
		)
		(fp_line
			(start -0.67945 -0.305054)
			(end -0.12065 -0.305054)
			(stroke
				(width 0.1)
				(type default)
			)
			(layer "F.Fab")
		)
		(fp_line
			(start -0.67945 0.3048)
			(end -0.67945 -0.305054)
			(stroke
				(width 0.1)
				(type default)
			)
			(layer "F.Fab")
		)
		(fp_line
			(start -0.12065 -0.305054)
			(end -0.12065 -0.2794)
			(stroke
				(width 0.1)
				(type default)
			)
			(layer "F.Fab")
		)
		(fp_line
			(start -0.12065 -0.2794)
			(end 0.12065 -0.2794)
			(stroke
				(width 0.1)
				(type default)
			)
			(layer "F.Fab")
		)
		(fp_line
			(start -0.12065 0.2794)
			(end -0.12065 0.3048)
			(stroke
				(width 0.1)
				(type default)
			)
			(layer "F.Fab")
		)
		(fp_line
			(start -0.12065 0.3048)
			(end -0.67945 0.3048)
			(stroke
				(width 0.1)
				(type default)
			)
			(layer "F.Fab")
		)
		(fp_line
			(start 0.120396 0.2794)
			(end -0.12065 0.2794)
			(stroke
				(width 0.1)
				(type default)
			)
			(layer "F.Fab")
		)
		(fp_line
			(start 0.120396 0.3048)
			(end 0.120396 0.2794)
			(stroke
				(width 0.1)
				(type default)
			)
			(layer "F.Fab")
		)
		(fp_line
			(start 0.12065 -0.3048)
			(end 0.67945 -0.3048)
			(stroke
				(width 0.1)
				(type default)
			)
			(layer "F.Fab")
		)
		(fp_line
			(start 0.12065 -0.2794)
			(end 0.12065 -0.3048)
			(stroke
				(width 0.1)
				(type default)
			)
			(layer "F.Fab")
		)
		(fp_line
			(start 0.67945 -0.3048)
			(end 0.67945 0.3048)
			(stroke
				(width 0.1)
				(type default)
			)
			(layer "F.Fab")
		)
		(fp_line
			(start 0.67945 0.3048)
			(end 0.120396 0.3048)
			(stroke
				(width 0.1)
				(type default)
			)
			(layer "F.Fab")
		)
		(pad "1" smd circle
			(at -0.40005 0)
			(size 0 0)
			(layers "F.Cu" "F.Mask" "F.Paste")
			(net "P3V3_AUX")
		)
		(pad "2" smd circle
			(at 0.40005 0)
			(size 0 0)
			(layers "F.Cu" "F.Mask" "F.Paste")
			(net "GND")
		)
	)
	(footprint ""
		(layer "F.Cu")
		(at 205.74 -135.763)
		(property "Reference" "R554"
			(at 0 0 0)
			(layer "F.SilkS")
			(hide yes)
			(effects
				(font
					(size 1.27 1.27)
				)
			)
		)
		(property "Value" ""
			(at 0 0 0)
			(layer "F.Fab")
			(effects
				(font
					(size 1.27 1.27)
				)
			)
		)
		(duplicate_pad_numbers_are_jumpers no)
		(fp_line
			(start -0.7874 -0.4064)
			(end 0.7874 -0.4064)
			(stroke
				(width 0.1524)
				(type default)
			)
			(layer "F.SilkS")
		)
		(fp_line
			(start -0.7874 0.4064)
			(end -0.7874 -0.4064)
			(stroke
				(width 0.1524)
				(type default)
			)
			(layer "F.SilkS")
		)
		(fp_line
			(start 0.7874 -0.4064)
			(end 0.7874 0.4064)
			(stroke
				(width 0.1524)
				(type default)
			)
			(layer "F.SilkS")
		)
		(fp_line
			(start 0.7874 0.4064)
			(end -0.7874 0.4064)
			(stroke
				(width 0.1524)
				(type default)
			)
			(layer "F.SilkS")
		)
		(fp_line
			(start -0.67945 -0.305054)
			(end -0.12065 -0.305054)
			(stroke
				(width 0.1)
				(type default)
			)
			(layer "F.Fab")
		)
		(fp_line
			(start -0.67945 0.3048)
			(end -0.67945 -0.305054)
			(stroke
				(width 0.1)
				(type default)
			)
			(layer "F.Fab")
		)
		(fp_line
			(start -0.12065 -0.305054)
			(end -0.12065 -0.2794)
			(stroke
				(width 0.1)
				(type default)
			)
			(layer "F.Fab")
		)
		(fp_line
			(start -0.12065 -0.2794)
			(end 0.12065 -0.2794)
			(stroke
				(width 0.1)
				(type default)
			)
			(layer "F.Fab")
		)
		(fp_line
			(start -0.12065 0.2794)
			(end -0.12065 0.3048)
			(stroke
				(width 0.1)
				(type default)
			)
			(layer "F.Fab")
		)
		(fp_line
			(start -0.12065 0.3048)
			(end -0.67945 0.3048)
			(stroke
				(width 0.1)
				(type default)
			)
			(layer "F.Fab")
		)
		(fp_line
			(start 0.120396 0.2794)
			(end -0.12065 0.2794)
			(stroke
				(width 0.1)
				(type default)
			)
			(layer "F.Fab")
		)
		(fp_line
			(start 0.120396 0.3048)
			(end 0.120396 0.2794)
			(stroke
				(width 0.1)
				(type default)
			)
			(layer "F.Fab")
		)
		(fp_line
			(start 0.12065 -0.3048)
			(end 0.67945 -0.3048)
			(stroke
				(width 0.1)
				(type default)
			)
			(layer "F.Fab")
		)
		(fp_line
			(start 0.12065 -0.2794)
			(end 0.12065 -0.3048)
			(stroke
				(width 0.1)
				(type default)
			)
			(layer "F.Fab")
		)
		(fp_line
			(start 0.67945 -0.3048)
			(end 0.67945 0.3048)
			(stroke
				(width 0.1)
				(type default)
			)
			(layer "F.Fab")
		)
		(fp_line
			(start 0.67945 0.3048)
			(end 0.120396 0.3048)
			(stroke
				(width 0.1)
				(type default)
			)
			(layer "F.Fab")
		)
		(pad "1" smd circle
			(at -0.40005 0)
			(size 0 0)
			(layers "F.Cu" "F.Mask" "F.Paste")
			(net "P12V_AUX")
		)
		(pad "2" smd circle
			(at 0.40005 0)
			(size 0 0)
			(layers "F.Cu" "F.Mask" "F.Paste")
			(net "SW_P3V3_EN_N")
		)
	)
	(footprint ""
		(layer "F.Cu")
		(at 24.765 -361.061)
		(property "Reference" "PR8012"
			(at 0 0 0)
			(layer "F.SilkS")
			(hide yes)
			(effects
				(font
					(size 1.27 1.27)
				)
			)
		)
		(property "Value" ""
			(at 0 0 0)
			(layer "F.Fab")
			(effects
				(font
					(size 1.27 1.27)
				)
			)
		)
		(duplicate_pad_numbers_are_jumpers no)
		(fp_line
			(start -0.7874 -0.4064)
			(end 0.7874 -0.4064)
			(stroke
				(width 0.1524)
				(type default)
			)
			(layer "F.SilkS")
		)
		(fp_line
			(start -0.7874 0.4064)
			(end -0.7874 -0.4064)
			(stroke
				(width 0.1524)
				(type default)
			)
			(layer "F.SilkS")
		)
		(fp_line
			(start 0.7874 -0.4064)
			(end 0.7874 0.4064)
			(stroke
				(width 0.1524)
				(type default)
			)
			(layer "F.SilkS")
		)
		(fp_line
			(start 0.7874 0.4064)
			(end -0.7874 0.4064)
			(stroke
				(width 0.1524)
				(type default)
			)
			(layer "F.SilkS")
		)
		(fp_line
			(start -0.67945 -0.305054)
			(end -0.12065 -0.305054)
			(stroke
				(width 0.1)
				(type default)
			)
			(layer "F.Fab")
		)
		(fp_line
			(start -0.67945 0.3048)
			(end -0.67945 -0.305054)
			(stroke
				(width 0.1)
				(type default)
			)
			(layer "F.Fab")
		)
		(fp_line
			(start -0.12065 -0.305054)
			(end -0.12065 -0.2794)
			(stroke
				(width 0.1)
				(type default)
			)
			(layer "F.Fab")
		)
		(fp_line
			(start -0.12065 -0.2794)
			(end 0.12065 -0.2794)
			(stroke
				(width 0.1)
				(type default)
			)
			(layer "F.Fab")
		)
		(fp_line
			(start -0.12065 0.2794)
			(end -0.12065 0.3048)
			(stroke
				(width 0.1)
				(type default)
			)
			(layer "F.Fab")
		)
		(fp_line
			(start -0.12065 0.3048)
			(end -0.67945 0.3048)
			(stroke
				(width 0.1)
				(type default)
			)
			(layer "F.Fab")
		)
		(fp_line
			(start 0.120396 0.2794)
			(end -0.12065 0.2794)
			(stroke
				(width 0.1)
				(type default)
			)
			(layer "F.Fab")
		)
		(fp_line
			(start 0.120396 0.3048)
			(end 0.120396 0.2794)
			(stroke
				(width 0.1)
				(type default)
			)
			(layer "F.Fab")
		)
		(fp_line
			(start 0.12065 -0.3048)
			(end 0.67945 -0.3048)
			(stroke
				(width 0.1)
				(type default)
			)
			(layer "F.Fab")
		)
		(fp_line
			(start 0.12065 -0.2794)
			(end 0.12065 -0.3048)
			(stroke
				(width 0.1)
				(type default)
			)
			(layer "F.Fab")
		)
		(fp_line
			(start 0.67945 -0.3048)
			(end 0.67945 0.3048)
			(stroke
				(width 0.1)
				(type default)
			)
			(layer "F.Fab")
		)
		(fp_line
			(start 0.67945 0.3048)
			(end 0.120396 0.3048)
			(stroke
				(width 0.1)
				(type default)
			)
			(layer "F.Fab")
		)
		(pad "1" smd circle
			(at -0.40005 0)
			(size 0 0)
			(layers "F.Cu" "F.Mask" "F.Paste")
			(net "SVID_PVDDCR_CPU1_P1_SVD_R")
		)
		(pad "2" smd circle
			(at 0.40005 0)
			(size 0 0)
			(layers "F.Cu" "F.Mask" "F.Paste")
			(net "SVID_PVDDCR_CPU1_P1_SVD_R1")
		)
	)
	(footprint ""
		(layer "F.Cu")
		(at 365.318548 -14.450568 -90)
		(property "Reference" "R820"
			(at 0 0 270)
			(layer "F.SilkS")
			(hide yes)
			(effects
				(font
					(size 1.27 1.27)
				)
			)
		)
		(property "Value" ""
			(at 0 0 270)
			(layer "F.Fab")
			(effects
				(font
					(size 1.27 1.27)
				)
			)
		)
		(duplicate_pad_numbers_are_jumpers no)
		(fp_line
			(start -0.7874 0.4064)
			(end -0.7874 -0.4064)
			(stroke
				(width 0.1524)
				(type default)
			)
			(layer "F.SilkS")
		)
		(fp_line
			(start 0.7874 0.4064)
			(end -0.7874 0.4064)
			(stroke
				(width 0.1524)
				(type default)
			)
			(layer "F.SilkS")
		)
		(fp_line
			(start -0.7874 -0.4064)
			(end 0.7874 -0.4064)
			(stroke
				(width 0.1524)
				(type default)
			)
			(layer "F.SilkS")
		)
		(fp_line
			(start 0.7874 -0.4064)
			(end 0.7874 0.4064)
			(stroke
				(width 0.1524)
				(type default)
			)
			(layer "F.SilkS")
		)
		(fp_line
			(start -0.67945 0.3048)
			(end -0.67945 -0.305054)
			(stroke
				(width 0.1)
				(type default)
			)
			(layer "F.Fab")
		)
		(fp_line
			(start -0.12065 0.3048)
			(end -0.67945 0.3048)
			(stroke
				(width 0.1)
				(type default)
			)
			(layer "F.Fab")
		)
		(fp_line
			(start 0.120396 0.3048)
			(end 0.120396 0.2794)
			(stroke
				(width 0.1)
				(type default)
			)
			(layer "F.Fab")
		)
		(fp_line
			(start 0.67945 0.3048)
			(end 0.120396 0.3048)
			(stroke
				(width 0.1)
				(type default)
			)
			(layer "F.Fab")
		)
		(fp_line
			(start -0.12065 0.2794)
			(end -0.12065 0.3048)
			(stroke
				(width 0.1)
				(type default)
			)
			(layer "F.Fab")
		)
		(fp_line
			(start 0.120396 0.2794)
			(end -0.12065 0.2794)
			(stroke
				(width 0.1)
				(type default)
			)
			(layer "F.Fab")
		)
		(fp_line
			(start -0.12065 -0.2794)
			(end 0.12065 -0.2794)
			(stroke
				(width 0.1)
				(type default)
			)
			(layer "F.Fab")
		)
		(fp_line
			(start 0.12065 -0.2794)
			(end 0.12065 -0.3048)
			(stroke
				(width 0.1)
				(type default)
			)
			(layer "F.Fab")
		)
		(fp_line
			(start 0.12065 -0.3048)
			(end 0.67945 -0.3048)
			(stroke
				(width 0.1)
				(type default)
			)
			(layer "F.Fab")
		)
		(fp_line
			(start 0.67945 -0.3048)
			(end 0.67945 0.3048)
			(stroke
				(width 0.1)
				(type default)
			)
			(layer "F.Fab")
		)
		(fp_line
			(start -0.67945 -0.305054)
			(end -0.12065 -0.305054)
			(stroke
				(width 0.1)
				(type default)
			)
			(layer "F.Fab")
		)
		(fp_line
			(start -0.12065 -0.305054)
			(end -0.12065 -0.2794)
			(stroke
				(width 0.1)
				(type default)
			)
			(layer "F.Fab")
		)
		(pad "1" smd circle
			(at -0.40005 0 270)
			(size 0 0)
			(layers "F.Cu" "F.Mask" "F.Paste")
			(net "UART_VCC_J13")
		)
		(pad "2" smd circle
			(at 0.40005 0 270)
			(size 0 0)
			(layers "F.Cu" "F.Mask" "F.Paste")
			(net "P5V_AUX")
		)
	)
)
